(kicad_pcb
	(version 20241229)
	(generator "pcbnew")
	(generator_version "9.0")
	(general
		(thickness 1.61)
		(legacy_teardrops no)
	)
	(paper "A3")
	(title_block
		(title "SO-DIMM DDR5 Tester")
		(date "2025-11-26")
		(rev "1.3.0")
		(comment 9 "footprints 310-314 of 627")
	)
	(layers
		(0 "F.Cu" signal)
		(4 "In1.Cu" power)
		(6 "In2.Cu" mixed)
		(8 "In3.Cu" power)
		(10 "In4.Cu" mixed)
		(12 "In5.Cu" power)
		(14 "In6.Cu" mixed)
		(16 "In7.Cu" power)
		(18 "In8.Cu" power)
		(20 "In9.Cu" mixed)
		(22 "In10.Cu" power)
		(2 "B.Cu" signal)
		(9 "F.Adhes" user "F.Adhesive")
		(11 "B.Adhes" user "B.Adhesive")
		(13 "F.Paste" user)
		(15 "B.Paste" user)
		(5 "F.SilkS" user "F.Silkscreen")
		(7 "B.SilkS" user "B.Silkscreen")
		(1 "F.Mask" user)
		(3 "B.Mask" user)
		(17 "Dwgs.User" user "User.Drawings")
		(19 "Cmts.User" user "User.Comments")
		(21 "Eco1.User" user "User.Eco1")
		(23 "Eco2.User" user "User.Eco2")
		(25 "Edge.Cuts" user)
		(27 "Margin" user)
		(31 "F.CrtYd" user "F.Courtyard")
		(29 "B.CrtYd" user "B.Courtyard")
		(35 "F.Fab" user)
		(33 "B.Fab" user)
	)
	(footprint "antmicro-footprints:TP_1206_SMD_RCW-0C"
		(layer "F.Cu")
		(at 204.789501 173.401 90)
		(property "Reference" "TP21"
			(at -2.29 -1.4 90)
			(layer "F.SilkS")
			(hide yes)
			(effects
				(font
					(size 0.7 0.7)
					(thickness 0.15)
				)
				(justify left bottom)
			)
		)
		(property "Value" "TP_1206_SMD_RCW-0C"
			(at -4.68 2.25 90)
			(layer "F.Fab")
			(effects
				(font
					(size 0.7 0.7)
					(thickness 0.15)
				)
				(justify left bottom)
			)
		)
		(property "Datasheet" "https://www.te.com/commerce/DocumentDelivery/DDEController?Action=srchrtrv&DocNm=1773266&DocType=DS&DocLang=English"
			(at 0 0 90)
			(layer "F.Fab")
			(hide yes)
			(effects
				(font
					(size 1.27 1.27)
					(thickness 0.15)
				)
			)
		)
		(property "Author" "Antmicro"
			(at 378.190501 -31.388501 0)
			(layer "F.Fab")
			(hide yes)
			(effects
				(font
					(size 1 1)
					(thickness 0.15)
				)
			)
		)
		(property "License" "Apache-2.0"
			(at 378.190501 -31.388501 0)
			(layer "F.Fab")
			(hide yes)
			(effects
				(font
					(size 1 1)
					(thickness 0.15)
				)
			)
		)
		(property "MPN" "RCW-0C"
			(at 378.190501 -31.388501 0)
			(layer "F.Fab")
			(hide yes)
			(effects
				(font
					(size 1 1)
					(thickness 0.15)
				)
			)
		)
		(property "Manufacturer" "TE Connectivity"
			(at 378.190501 -31.388501 0)
			(layer "F.Fab")
			(hide yes)
			(effects
				(font
					(size 1 1)
					(thickness 0.15)
				)
			)
		)
		(sheetname "/Supply/")
		(sheetfile "supply.kicad_sch")
		(attr smd)
		(fp_line
			(start 1.78 -0.981)
			(end 1.281 -0.981)
			(stroke
				(width 0.15)
				(type solid)
			)
			(layer "F.SilkS")
		)
		(fp_line
			(start 1.78 -0.981)
			(end 1.78 -0.479)
			(stroke
				(width 0.15)
				(type solid)
			)
			(layer "F.SilkS")
		)
		(fp_line
			(start -1.779 -0.981)
			(end -1.279 -0.981)
			(stroke
				(width 0.15)
				(type solid)
			)
			(layer "F.SilkS")
		)
		(fp_line
			(start -1.779 -0.981)
			(end -1.779 -0.479)
			(stroke
				(width 0.15)
				(type solid)
			)
			(layer "F.SilkS")
		)
		(fp_line
			(start -1.779 0.482)
			(end -1.779 0.98)
			(stroke
				(width 0.15)
				(type solid)
			)
			(layer "F.SilkS")
		)
		(fp_line
			(start -1.779 0.98)
			(end -1.279 0.98)
			(stroke
				(width 0.15)
				(type solid)
			)
			(layer "F.SilkS")
		)
		(fp_line
			(start 1.78 0.982)
			(end 1.78 0.482)
			(stroke
				(width 0.15)
				(type solid)
			)
			(layer "F.SilkS")
		)
		(fp_line
			(start 1.78 0.982)
			(end 1.281 0.982)
			(stroke
				(width 0.15)
				(type solid)
			)
			(layer "F.SilkS")
		)
		(fp_rect
			(start -2.101 -1.314)
			(end 2.1 1.312)
			(stroke
				(width 0.05)
				(type solid)
			)
			(fill no)
			(layer "F.CrtYd")
		)
		(fp_rect
			(start -1.601 -0.814)
			(end 1.6 0.812)
			(stroke
				(width 0.15)
				(type solid)
			)
			(fill no)
			(layer "F.Fab")
		)
		(pad "1" smd rect
			(at 0 0 90)
			(size 3.4 1.8)
			(layers "F.Cu" "F.Mask" "F.Paste")
			(net 1 "GND")
			(pinfunction "1")
			(pintype "passive")
		)
	)
	(footprint "antmicro-footprints:SOD-523"
		(layer "F.Cu")
		(at 104.650001 184.485 180)
		(property "Reference" "D15"
			(at 0 -0.75 180)
			(layer "F.SilkS")
			(hide yes)
			(effects
				(font
					(size 0.7 0.7)
					(thickness 0.15)
				)
				(justify left bottom)
			)
		)
		(property "Value" "BAT54-02V-G3-08"
			(at 0 1.499 180)
			(layer "F.Fab")
			(effects
				(font
					(size 0.7 0.7)
					(thickness 0.15)
				)
				(justify left bottom)
			)
		)
		(property "Datasheet" "https://www.vishay.com/docs/85633/bat5402v.pdf"
			(at 0 0 180)
			(layer "F.Fab")
			(hide yes)
			(effects
				(font
					(size 1.27 1.27)
					(thickness 0.15)
				)
			)
		)
		(property "Description" "Small Signal Schottky Diode, Single, 30 V, 200 mA, 800 mV, 600 mA, 125 °C"
			(at 0 0 180)
			(layer "F.Fab")
			(hide yes)
			(effects
				(font
					(size 1.27 1.27)
					(thickness 0.15)
				)
			)
		)
		(property "Author" "Antmicro"
			(at 209.300002 368.97 0)
			(layer "F.Fab")
			(hide yes)
			(effects
				(font
					(size 1 1)
					(thickness 0.15)
				)
			)
		)
		(property "License" "Apache-2.0"
			(at 209.300002 368.97 0)
			(layer "F.Fab")
			(hide yes)
			(effects
				(font
					(size 1 1)
					(thickness 0.15)
				)
			)
		)
		(property "MPN" "BAT54-02V-G3-08"
			(at 209.300002 368.97 0)
			(layer "F.Fab")
			(hide yes)
			(effects
				(font
					(size 1 1)
					(thickness 0.15)
				)
			)
		)
		(property "Manufacturer" "Vishay"
			(at 209.300002 368.97 0)
			(layer "F.Fab")
			(hide yes)
			(effects
				(font
					(size 1 1)
					(thickness 0.15)
				)
			)
		)
		(sheetname "/Debug FTDI/")
		(sheetfile "debug-ftdi.kicad_sch")
		(attr smd)
		(fp_line
			(start -0.35 -0.5)
			(end -0.35 0.5)
			(stroke
				(width 0.15)
				(type solid)
			)
			(layer "F.SilkS")
		)
		(fp_rect
			(start -1 -0.6)
			(end 1 0.6)
			(stroke
				(width 0.05)
				(type solid)
			)
			(fill no)
			(layer "F.CrtYd")
		)
		(fp_line
			(start 0.65 -0.425)
			(end 0.65 0.423)
			(stroke
				(width 0.15)
				(type solid)
			)
			(layer "F.Fab")
		)
		(fp_line
			(start -0.35 -0.4)
			(end -0.35 0.4)
			(stroke
				(width 0.15)
				(type solid)
			)
			(layer "F.Fab")
		)
		(fp_line
			(start -0.652 0.423)
			(end 0.65 0.423)
			(stroke
				(width 0.15)
				(type solid)
			)
			(layer "F.Fab")
		)
		(fp_line
			(start -0.652 0.423)
			(end -0.652 -0.425)
			(stroke
				(width 0.15)
				(type solid)
			)
			(layer "F.Fab")
		)
		(fp_line
			(start -0.652 -0.425)
			(end 0.65 -0.425)
			(stroke
				(width 0.15)
				(type solid)
			)
			(layer "F.Fab")
		)
		(pad "1" smd roundrect
			(at -0.701 0 180)
			(size 0.5 0.6)
			(layers "F.Cu" "F.Mask" "F.Paste")
			(roundrect_rratio 0.25)
			(net 37 "/Debug FTDI/FTDI_SDA_OUT")
			(pinfunction "C")
			(pintype "passive")
		)
		(pad "2" smd roundrect
			(at 0.699 0 180)
			(size 0.5 0.6)
			(layers "F.Cu" "F.Mask" "F.Paste")
			(roundrect_rratio 0.25)
			(net 43 "/Debug FTDI/FTDI_SDA_IN")
			(pinfunction "A")
			(pintype "passive")
		)
	)
	(footprint "antmicro-footprints:SC70-3"
		(layer "F.Cu")
		(at 102.100501 118.176 180)
		(property "Reference" "Q11"
			(at 0 -1.6 180)
			(layer "F.SilkS")
			(hide yes)
			(effects
				(font
					(size 0.7 0.7)
					(thickness 0.15)
				)
				(justify left bottom)
			)
		)
		(property "Value" "BSS138PW,115"
			(at 0 2.3 180)
			(layer "F.Fab")
			(effects
				(font
					(size 0.7 0.7)
					(thickness 0.15)
				)
				(justify left bottom)
			)
		)
		(property "Datasheet" "https://assets.nexperia.com/documents/data-sheet/BSS138PW.pdf"
			(at 0 0 180)
			(layer "F.Fab")
			(hide yes)
			(effects
				(font
					(size 1.27 1.27)
					(thickness 0.15)
				)
			)
		)
		(property "Description" "Power MOSFET, N Channel, 60 V, 320 mA, 0.9 ohm, SOT-323, Surface Mount"
			(at 0 0 180)
			(layer "F.Fab")
			(hide yes)
			(effects
				(font
					(size 1.27 1.27)
					(thickness 0.15)
				)
			)
		)
		(property "Author" "Antmicro"
			(at 204.201002 236.352 0)
			(layer "F.Fab")
			(hide yes)
			(effects
				(font
					(size 1 1)
					(thickness 0.15)
				)
			)
		)
		(property "License" "Apache-2.0"
			(at 204.201002 236.352 0)
			(layer "F.Fab")
			(hide yes)
			(effects
				(font
					(size 1 1)
					(thickness 0.15)
				)
			)
		)
		(property "MPN" "BSS138PW,115"
			(at 204.201002 236.352 0)
			(layer "F.Fab")
			(hide yes)
			(effects
				(font
					(size 1 1)
					(thickness 0.15)
				)
			)
		)
		(property "Manufacturer" "Nexperia"
			(at 204.201002 236.352 0)
			(layer "F.Fab")
			(hide yes)
			(effects
				(font
					(size 1 1)
					(thickness 0.15)
				)
			)
		)
		(sheetname "/DDR5 SODIMM/")
		(sheetfile "ddr5-sodimm.kicad_sch")
		(attr smd)
		(fp_line
			(start 0.627 0.6)
			(end 0.627 1.001)
			(stroke
				(width 0.15)
				(type solid)
			)
			(layer "F.SilkS")
		)
		(fp_line
			(start 0.627 -0.6)
			(end 0.627 -0.999)
			(stroke
				(width 0.15)
				(type solid)
			)
			(layer "F.SilkS")
		)
		(fp_line
			(start -0.3 1)
			(end 0.627 1.001)
			(stroke
				(width 0.15)
				(type solid)
			)
			(layer "F.SilkS")
		)
		(fp_line
			(start -0.3 -1)
			(end 0.627 -0.999)
			(stroke
				(width 0.15)
				(type solid)
			)
			(layer "F.SilkS")
		)
		(fp_line
			(start 1.4 0.4)
			(end 0.9 0.4)
			(stroke
				(width 0.05)
				(type solid)
			)
			(layer "F.CrtYd")
		)
		(fp_line
			(start 1.4 -0.4)
			(end 1.4 0.4)
			(stroke
				(width 0.05)
				(type solid)
			)
			(layer "F.CrtYd")
		)
		(fp_line
			(start 0.9 1.3)
			(end -0.9 1.3)
			(stroke
				(width 0.05)
				(type solid)
			)
			(layer "F.CrtYd")
		)
		(fp_line
			(start 0.9 0.4)
			(end 0.9 1.3)
			(stroke
				(width 0.05)
				(type solid)
			)
			(layer "F.CrtYd")
		)
		(fp_line
			(start 0.9 -0.4)
			(end 1.4 -0.4)
			(stroke
				(width 0.05)
				(type solid)
			)
			(layer "F.CrtYd")
		)
		(fp_line
			(start 0.9 -1.3)
			(end 0.9 -0.4)
			(stroke
				(width 0.05)
				(type solid)
			)
			(layer "F.CrtYd")
		)
		(fp_line
			(start -0.9 1.3)
			(end -0.9 1)
			(stroke
				(width 0.05)
				(type solid)
			)
			(layer "F.CrtYd")
		)
		(fp_line
			(start -0.9 1)
			(end -1.4 1)
			(stroke
				(width 0.05)
				(type solid)
			)
			(layer "F.CrtYd")
		)
		(fp_line
			(start -0.9 -1)
			(end -1.4 -1)
			(stroke
				(width 0.05)
				(type solid)
			)
			(layer "F.CrtYd")
		)
		(fp_line
			(start -0.9 -1.3)
			(end 0.9 -1.3)
			(stroke
				(width 0.05)
				(type solid)
			)
			(layer "F.CrtYd")
		)
		(fp_line
			(start -0.9 -1.3)
			(end -0.9 -1)
			(stroke
				(width 0.05)
				(type solid)
			)
			(layer "F.CrtYd")
		)
		(fp_line
			(start -1.4 1)
			(end -1.4 -1)
			(stroke
				(width 0.05)
				(type solid)
			)
			(layer "F.CrtYd")
		)
		(fp_rect
			(start -0.623 -0.999)
			(end 0.627 1.001)
			(stroke
				(width 0.15)
				(type solid)
			)
			(fill no)
			(layer "F.Fab")
		)
		(pad "1" smd rect
			(at -1.051 -0.65 270)
			(size 0.6 0.6)
			(layers "F.Cu" "F.Mask" "F.Paste")
			(net 236 "HOT_SWAP_RED")
			(pinfunction "G")
			(pintype "input")
		)
		(pad "2" smd rect
			(at -1.051 0.65 270)
			(size 0.6 0.6)
			(layers "F.Cu" "F.Mask" "F.Paste")
			(net 1 "GND")
			(pinfunction "S")
			(pintype "passive")
		)
		(pad "3" smd rect
			(at 1.05 0 270)
			(size 0.6 0.6)
			(layers "F.Cu" "F.Mask" "F.Paste")
			(net 364 "Net-(Q11-D)")
			(pinfunction "D")
			(pintype "passive")
		)
	)
	(footprint "antmicro-footprints:R_0402_1005Metric"
		(layer "F.Cu")
		(at 100.260501 146.556 180)
		(descr "Resistor SMD 0402")
		(tags "resistor SMD 0402")
		(property "Reference" "R122"
			(at -1.122484 -0.772697 180)
			(layer "F.SilkS")
			(hide yes)
			(effects
				(font
					(size 0.7 0.7)
					(thickness 0.15)
				)
				(justify left bottom)
			)
		)
		(property "Value" "R_4k7_0402"
			(at -1.011843 1.772047 180)
			(layer "F.Fab")
			(effects
				(font
					(size 0.7 0.7)
					(thickness 0.15)
				)
				(justify left bottom)
			)
		)
		(property "Datasheet" "https://www.bourns.com/docs/product-datasheets/cr.pdf"
			(at 0 0 180)
			(layer "F.Fab")
			(hide yes)
			(effects
				(font
					(size 1.27 1.27)
					(thickness 0.15)
				)
			)
		)
		(property "Author" "Antmicro"
			(at 200.521002 293.112 0)
			(layer "F.Fab")
			(hide yes)
			(effects
				(font
					(size 1 1)
					(thickness 0.15)
				)
			)
		)
		(property "License" "Apache-2.0"
			(at 200.521002 293.112 0)
			(layer "F.Fab")
			(hide yes)
			(effects
				(font
					(size 1 1)
					(thickness 0.15)
				)
			)
		)
		(property "MPN" "CR0402-FX-4701GLF"
			(at 200.521002 293.112 0)
			(layer "F.Fab")
			(hide yes)
			(effects
				(font
					(size 1 1)
					(thickness 0.15)
				)
			)
		)
		(property "Manufacturer" "Bourns"
			(at 200.521002 293.112 0)
			(layer "F.Fab")
			(hide yes)
			(effects
				(font
					(size 1 1)
					(thickness 0.15)
				)
			)
		)
		(property "Tolerance" "1%"
			(at 200.521002 293.112 0)
			(layer "F.Fab")
			(hide yes)
			(effects
				(font
					(size 1 1)
					(thickness 0.15)
				)
			)
		)
		(property "Val" "4k7"
			(at 200.521002 293.112 0)
			(layer "F.Fab")
			(hide yes)
			(effects
				(font
					(size 1 1)
					(thickness 0.15)
				)
			)
		)
		(sheetname "/I^{2}C/")
		(sheetfile "i2c.kicad_sch")
		(attr smd)
		(fp_rect
			(start -0.93 -0.47)
			(end 0.93 0.47)
			(stroke
				(width 0.05)
				(type solid)
			)
			(fill no)
			(layer "F.CrtYd")
		)
		(fp_rect
			(start -0.5 -0.25)
			(end 0.5 0.25)
			(stroke
				(width 0.15)
				(type solid)
			)
			(fill no)
			(layer "F.Fab")
		)
		(pad "1" smd roundrect
			(at -0.485 0 180)
			(size 0.59 0.64)
			(layers "F.Cu" "F.Mask" "F.Paste")
			(roundrect_rratio 0.25)
			(net 200 "+3V3")
			(pintype "passive")
		)
		(pad "2" smd roundrect
			(at 0.485 0 180)
			(size 0.59 0.64)
			(layers "F.Cu" "F.Mask" "F.Paste")
			(roundrect_rratio 0.25)
			(net 682 "/FPGA bank 14/FPGA_DDR.SCL")
			(pintype "passive")
		)
	)
	(footprint "antmicro-footprints:LED_0603_1608Metric_G"
		(layer "F.Cu")
		(at 86.350501 116.426 -90)
		(descr "LED SMD 0603 Green")
		(tags "LED SMD 0603 Green")
		(property "Reference" "D6"
			(at -0.001 -0.901 270)
			(layer "F.SilkS")
			(hide yes)
			(effects
				(font
					(size 0.7 0.7)
					(thickness 0.15)
				)
				(justify left bottom)
			)
		)
		(property "Value" "LED_G_0603_KP-1608CGCK"
			(at -0.001 1.599 270)
			(layer "F.Fab")
			(effects
				(font
					(size 0.7 0.7)
					(thickness 0.15)
				)
				(justify left bottom)
			)
		)
		(property "Datasheet" "http://www.farnell.com/datasheets/2045956.pdf"
			(at 0 0 270)
			(layer "F.Fab")
			(hide yes)
			(effects
				(font
					(size 1.27 1.27)
					(thickness 0.15)
				)
			)
		)
		(property "Author" "Antmicro"
			(at -30.075499 202.776501 0)
			(layer "F.Fab")
			(hide yes)
			(effects
				(font
					(size 1 1)
					(thickness 0.15)
				)
			)
		)
		(property "License" "Apache-2.0"
			(at -30.075499 202.776501 0)
			(layer "F.Fab")
			(hide yes)
			(effects
				(font
					(size 1 1)
					(thickness 0.15)
				)
			)
		)
		(property "MPN" "KP-1608CGCK"
			(at -30.075499 202.776501 0)
			(layer "F.Fab")
			(hide yes)
			(effects
				(font
					(size 1 1)
					(thickness 0.15)
				)
			)
		)
		(property "Manufacturer" "Kingbright"
			(at -30.075499 202.776501 0)
			(layer "F.Fab")
			(hide yes)
			(effects
				(font
					(size 1 1)
					(thickness 0.15)
				)
			)
		)
		(sheetname "/FPGA bank 14/")
		(sheetfile "fpga-bank-14.kicad_sch")
		(attr smd)
		(fp_line
			(start -0.271 0.348)
			(end 0.269 0.348)
			(stroke
				(width 0.15)
				(type solid)
			)
			(layer "F.SilkS")
		)
		(fp_line
			(start 1.249 0.319)
			(end 1.249 -0.321)
			(stroke
				(width 0.15)
				(type solid)
			)
			(layer "F.SilkS")
		)
		(fp_line
			(start -0.107 -0.001)
			(end -0.291 -0.001)
			(stroke
				(width 0.1)
				(type solid)
			)
			(layer "F.SilkS")
		)
		(fp_line
			(start 0.092 -0.001)
			(end -0.107 0.198)
			(stroke
				(width 0.1)
				(type solid)
			)
			(layer "F.SilkS")
		)
		(fp_line
			(start 0.092 -0.001)
			(end 0.292 -0.001)
			(stroke
				(width 0.1)
				(type solid)
			)
			(layer "F.SilkS")
		)
		(fp_line
			(start -0.107 -0.201)
			(end -0.107 0.198)
			(stroke
				(width 0.1)
				(type solid)
			)
			(layer "F.SilkS")
		)
		(fp_line
			(start -0.107 -0.201)
			(end 0.092 -0.001)
			(stroke
				(width 0.1)
				(type solid)
			)
			(layer "F.SilkS")
		)
		(fp_line
			(start 0.092 -0.201)
			(end 0.092 0.198)
			(stroke
				(width 0.1)
				(type solid)
			)
			(layer "F.SilkS")
		)
		(fp_line
			(start -0.271 -0.349)
			(end 0.269 -0.349)
			(stroke
				(width 0.15)
				(type solid)
			)
			(layer "F.SilkS")
		)
		(fp_rect
			(start -1.2192 -0.6096)
			(end 1.27 0.6016)
			(stroke
				(width 0.05)
				(type solid)
			)
			(fill no)
			(layer "F.CrtYd")
		)
		(fp_line
			(start -0.202 0.201)
			(end 0.1 -0.001)
			(stroke
				(width 0.15)
				(type solid)
			)
			(layer "F.Fab")
		)
		(fp_line
			(start 0.198 0.201)
			(end 0.198 -0.101)
			(stroke
				(width 0.15)
				(type solid)
			)
			(layer "F.Fab")
		)
		(fp_line
			(start -0.849 0.025)
			(end -0.442 0.381)
			(stroke
				(width 0.15)
				(type solid)
			)
			(layer "F.Fab")
		)
		(fp_line
			(start -0.6 -0.001)
			(end -0.202 -0.001)
			(stroke
				(width 0.15)
				(type solid)
			)
			(layer "F.Fab")
		)
		(fp_line
			(start -0.202 -0.001)
			(end -0.202 0.201)
			(stroke
				(width 0.15)
				(type solid)
			)
			(layer "F.Fab")
		)
		(fp_line
			(start 0.1 -0.001)
			(end -0.202 -0.201)
			(stroke
				(width 0.15)
				(type solid)
			)
			(layer "F.Fab")
		)
		(fp_line
			(start 0.198 -0.001)
			(end 0.596 -0.001)
			(stroke
				(width 0.15)
				(type solid)
			)
			(layer "F.Fab")
		)
		(fp_line
			(start -0.202 -0.201)
			(end -0.202 -0.001)
			(stroke
				(width 0.15)
				(type solid)
			)
			(layer "F.Fab")
		)
		(fp_line
			(start 0.198 -0.201)
			(end 0.198 -0.101)
			(stroke
				(width 0.15)
				(type solid)
			)
			(layer "F.Fab")
		)
		(fp_rect
			(start -0.849 -0.401)
			(end 0.849 0.401)
			(stroke
				(width 0.15)
				(type solid)
			)
			(fill no)
			(layer "F.Fab")
		)
		(pad "1" smd rect
			(at -0.751 -0.001 90)
			(size 0.8 0.8)
			(layers "F.Cu" "F.Mask" "F.Paste")
			(net 200 "+3V3")
			(pinfunction "1")
			(pintype "passive")
		)
		(pad "2" smd rect
			(at 0.749 -0.001 90)
			(size 0.8 0.8)
			(layers "F.Cu" "F.Mask" "F.Paste")
			(net 309 "Net-(D6-Pad2)")
			(pinfunction "2")
			(pintype "passive")
		)
	)
)
